(kicad_pcb
	(version 20241229)
	(generator "pcbnew")
	(generator_version "9.0")
	(general
		(thickness 1.711)
		(legacy_teardrops no)
	)
	(paper "A4")
	(title_block
		(title "Antmicro Baseboard for Jetson AGX Thor")
		(date "2026-02-18")
		(rev "1.1.0")
		(company "Antmicro Ltd")
		(comment 1 "www.antmicro.com")
		(comment 9 "footprints 430-434 of 1170")
	)
	(layers
		(0 "F.Cu" signal)
		(4 "In1.Cu" signal)
		(6 "In2.Cu" signal)
		(8 "In3.Cu" signal)
		(10 "In4.Cu" jumper)
		(12 "In5.Cu" signal)
		(14 "In6.Cu" signal)
		(16 "In7.Cu" signal)
		(18 "In8.Cu" signal)
		(2 "B.Cu" signal)
		(9 "F.Adhes" user "F.Adhesive")
		(11 "B.Adhes" user "B.Adhesive")
		(13 "F.Paste" user)
		(15 "B.Paste" user)
		(5 "F.SilkS" user "F.Silkscreen")
		(7 "B.SilkS" user "B.Silkscreen")
		(1 "F.Mask" user)
		(3 "B.Mask" user)
		(17 "Dwgs.User" user "User.Drawings")
		(19 "Cmts.User" user "User.Comments")
		(21 "Eco1.User" user "User.Eco1")
		(23 "Eco2.User" user "User.Eco2")
		(25 "Edge.Cuts" user)
		(27 "Margin" user)
		(31 "F.CrtYd" user "F.Courtyard")
		(29 "B.CrtYd" user "B.Courtyard")
		(35 "F.Fab" user)
		(33 "B.Fab" user)
	)
	(footprint "antmicro-footprints:QFN-2L_1.6x1x0.55mm"
		(layer "F.Cu")
		(at 167.6 142.3 90)
		(property "Reference" "D64"
			(at -1.1 1.5 90)
			(layer "F.SilkS")
			(effects
				(font
					(size 0.7 0.7)
					(thickness 0.15)
				)
				(justify left bottom)
			)
		)
		(property "Value" "ESDA25P35-1U1M"
			(at 0 1.7 90)
			(layer "F.Fab")
			(effects
				(font
					(size 0.7 0.7)
					(thickness 0.15)
				)
				(justify left bottom)
			)
		)
		(property "Datasheet" "https://www.st.com/resource/en/datasheet/esda25p35-1u1m.pdf"
			(at 0 0 90)
			(layer "F.Fab")
			(hide yes)
			(effects
				(font
					(size 1.27 1.27)
					(thickness 0.15)
				)
			)
		)
		(property "Description" "Unidirectional TVS, 30 kV, QFN-2L, 22 V, 195 pF"
			(at 0 0 90)
			(layer "F.Fab")
			(hide yes)
			(effects
				(font
					(size 1.27 1.27)
					(thickness 0.15)
				)
			)
		)
		(property "MPN" "ESDA25P35-1U1M"
			(at 0 0 90)
			(unlocked yes)
			(layer "F.Fab")
			(hide yes)
			(effects
				(font
					(size 1 1)
					(thickness 0.15)
				)
			)
		)
		(property "Manufacturer" "STMicroelectronics"
			(at 0 0 90)
			(unlocked yes)
			(layer "F.Fab")
			(hide yes)
			(effects
				(font
					(size 1 1)
					(thickness 0.15)
				)
			)
		)
		(property "Author" "Antmicro"
			(at 0 0 90)
			(unlocked yes)
			(layer "F.Fab")
			(hide yes)
			(effects
				(font
					(size 1 1)
					(thickness 0.15)
				)
			)
		)
		(property "License" "Apache-2.0"
			(at 0 0 90)
			(unlocked yes)
			(layer "F.Fab")
			(hide yes)
			(effects
				(font
					(size 1 1)
					(thickness 0.15)
				)
			)
		)
		(sheetname "/Peripherals/")
		(sheetfile "peripherals.kicad_sch")
		(attr smd)
		(fp_line
			(start 0.23 -0.45)
			(end -0.23 -0.45)
			(stroke
				(width 0.15)
				(type solid)
			)
			(layer "F.SilkS")
		)
		(fp_line
			(start -1.2 -0.4)
			(end -1.2 0.4)
			(stroke
				(width 0.15)
				(type solid)
			)
			(layer "F.SilkS")
		)
		(fp_line
			(start 0.23 0.45)
			(end -0.23 0.45)
			(stroke
				(width 0.15)
				(type solid)
			)
			(layer "F.SilkS")
		)
		(fp_rect
			(start 1.25 0.65)
			(end -1.25 -0.65)
			(stroke
				(width 0.05)
				(type solid)
			)
			(fill no)
			(layer "F.CrtYd")
		)
		(fp_line
			(start 0.201 -0.202)
			(end -0.101 0)
			(stroke
				(width 0.15)
				(type solid)
			)
			(layer "F.Fab")
		)
		(fp_line
			(start -0.199 -0.202)
			(end -0.199 0.1)
			(stroke
				(width 0.15)
				(type solid)
			)
			(layer "F.Fab")
		)
		(fp_line
			(start 0.599 0)
			(end 0.201 0)
			(stroke
				(width 0.15)
				(type solid)
			)
			(layer "F.Fab")
		)
		(fp_line
			(start 0.201 0)
			(end 0.201 -0.202)
			(stroke
				(width 0.15)
				(type solid)
			)
			(layer "F.Fab")
		)
		(fp_line
			(start -0.101 0)
			(end 0.201 0.2)
			(stroke
				(width 0.15)
				(type solid)
			)
			(layer "F.Fab")
		)
		(fp_line
			(start -0.199 0)
			(end -0.597 0)
			(stroke
				(width 0.15)
				(type solid)
			)
			(layer "F.Fab")
		)
		(fp_line
			(start 0.201 0.2)
			(end 0.201 0)
			(stroke
				(width 0.15)
				(type solid)
			)
			(layer "F.Fab")
		)
		(fp_line
			(start -0.199 0.2)
			(end -0.199 0.1)
			(stroke
				(width 0.15)
				(type solid)
			)
			(layer "F.Fab")
		)
		(fp_rect
			(start 0.848 0.4)
			(end -0.85 -0.402)
			(stroke
				(width 0.15)
				(type solid)
			)
			(fill no)
			(layer "F.Fab")
		)
		(fp_text user "${REFERENCE}"
			(at -1.31 3.769 90)
			(layer "F.Fab")
			(effects
				(font
					(size 0.7 0.7)
					(thickness 0.15)
				)
				(justify left bottom)
			)
		)
		(fp_text user "Author: Antmicro"
			(at -1.31 4.769 90)
			(layer "F.Fab")
			(effects
				(font
					(size 0.7 0.7)
					(thickness 0.15)
				)
				(justify left bottom)
			)
		)
		(fp_text user "License: Apache-2.0"
			(at -1.31 5.769 90)
			(layer "F.Fab")
			(effects
				(font
					(size 0.7 0.7)
					(thickness 0.15)
				)
				(justify left bottom)
			)
		)
		(pad "1" smd roundrect
			(at -0.7 0 270)
			(size 0.8 1)
			(layers "F.Cu" "F.Mask" "F.Paste")
			(roundrect_rratio 0.2)
			(net 634 "+12V")
			(pinfunction "C")
			(pintype "passive")
		)
		(pad "2" smd roundrect
			(at 0.7 0 270)
			(size 0.8 1)
			(layers "F.Cu" "F.Mask" "F.Paste")
			(roundrect_rratio 0.2)
			(net 1 "GND")
			(pinfunction "A")
			(pintype "passive")
		)
	)
	(footprint "antmicro-footprints:R_0402_1005Metric"
		(layer "F.Cu")
		(at 196.9 98.82 -90)
		(descr "Resistor SMD 0402")
		(tags "resistor SMD 0402")
		(property "Reference" "R388"
			(at -0.72 3.5 90)
			(layer "F.SilkS")
			(effects
				(font
					(size 0.7 0.7)
					(thickness 0.15)
				)
				(justify right top)
			)
		)
		(property "Value" "R_0R_0402"
			(at -1.011843 1.772047 90)
			(layer "F.Fab")
			(effects
				(font
					(size 0.7 0.7)
					(thickness 0.15)
				)
				(justify right top)
			)
		)
		(property "Datasheet" "https://industrial.panasonic.com/cdbs/www-data/pdf/RDA0000/AOA0000C301.pdf"
			(at 0 0 90)
			(layer "F.Fab")
			(hide yes)
			(effects
				(font
					(size 1.27 1.27)
					(thickness 0.15)
				)
			)
		)
		(property "Description" "SMD Chip Resistor, Jumper, 0 ohm, 100 mW, 0402 [1005 Metric], Thick Film, General Purpose"
			(at 0 0 90)
			(layer "F.Fab")
			(hide yes)
			(effects
				(font
					(size 1.27 1.27)
					(thickness 0.15)
				)
			)
		)
		(property "MPN" "ERJ2GE0R00X"
			(at 0 0 270)
			(unlocked yes)
			(layer "F.Fab")
			(hide yes)
			(effects
				(font
					(size 1 1)
					(thickness 0.15)
				)
			)
		)
		(property "Manufacturer" "Panasonic"
			(at 0 0 270)
			(unlocked yes)
			(layer "F.Fab")
			(hide yes)
			(effects
				(font
					(size 1 1)
					(thickness 0.15)
				)
			)
		)
		(property "License" "Apache-2.0"
			(at 0 0 270)
			(unlocked yes)
			(layer "F.Fab")
			(hide yes)
			(effects
				(font
					(size 1 1)
					(thickness 0.15)
				)
			)
		)
		(property "Author" "Antmicro"
			(at 0 0 270)
			(unlocked yes)
			(layer "F.Fab")
			(hide yes)
			(effects
				(font
					(size 1 1)
					(thickness 0.15)
				)
			)
		)
		(property "Val" "0R"
			(at 0 0 270)
			(unlocked yes)
			(layer "F.Fab")
			(hide yes)
			(effects
				(font
					(size 1 1)
					(thickness 0.15)
				)
			)
		)
		(property "Tolerance" "~"
			(at 0 0 270)
			(unlocked yes)
			(layer "F.Fab")
			(hide yes)
			(effects
				(font
					(size 1 1)
					(thickness 0.15)
				)
			)
		)
		(property "Current" "1A"
			(at 0 0 270)
			(unlocked yes)
			(layer "F.Fab")
			(hide yes)
			(effects
				(font
					(size 1 1)
					(thickness 0.15)
				)
			)
		)
		(sheetname "/USB Debug, PD/")
		(sheetfile "usb_debug_pd.kicad_sch")
		(attr smd exclude_from_pos_files exclude_from_bom dnp)
		(fp_rect
			(start -0.925 -0.47)
			(end 0.925 0.47)
			(stroke
				(width 0.05)
				(type default)
			)
			(fill no)
			(layer "F.CrtYd")
		)
		(fp_rect
			(start -0.5 -0.25)
			(end 0.5 0.25)
			(stroke
				(width 0.15)
				(type solid)
			)
			(fill no)
			(layer "F.Fab")
		)
		(fp_text user "License: Apache-2.0"
			(at -0.95 5.169 90)
			(layer "F.Fab")
			(effects
				(font
					(size 0.7 0.7)
					(thickness 0.15)
				)
				(justify right top)
			)
		)
		(fp_text user "Author: Antmicro"
			(at -0.95 4.169 90)
			(layer "F.Fab")
			(effects
				(font
					(size 0.7 0.7)
					(thickness 0.15)
				)
				(justify right top)
			)
		)
		(fp_text user "${REFERENCE}"
			(at -0.95 3.168 90)
			(layer "F.Fab")
			(effects
				(font
					(size 0.7 0.7)
					(thickness 0.15)
				)
				(justify right top)
			)
		)
		(pad "1" smd roundrect
			(at -0.48 0 270)
			(size 0.59 0.64)
			(layers "F.Cu" "F.Mask" "F.Paste")
			(roundrect_rratio 0.25)
			(net 811 "/USB Debug, PD/MOSI")
			(pintype "passive")
		)
		(pad "2" smd roundrect
			(at 0.48 0 270)
			(size 0.59 0.64)
			(layers "F.Cu" "F.Mask" "F.Paste")
			(roundrect_rratio 0.25)
			(net 850 "/I2C_{SYS}.SDA")
			(pintype "passive")
		)
	)
	(footprint "antmicro-footprints:R_0402_1005Metric"
		(layer "F.Cu")
		(at 147.8 119.2)
		(descr "Resistor SMD 0402")
		(tags "resistor SMD 0402")
		(property "Reference" "R373"
			(at -3.7 0.5 0)
			(layer "F.SilkS")
			(effects
				(font
					(size 0.7 0.7)
					(thickness 0.15)
				)
				(justify left bottom)
			)
		)
		(property "Value" "R_2k2_0402"
			(at -1.011843 1.772047 0)
			(layer "F.Fab")
			(effects
				(font
					(size 0.7 0.7)
					(thickness 0.15)
				)
				(justify left bottom)
			)
		)
		(property "Datasheet" "https://www.bourns.com/docs/product-datasheets/cr.pdf"
			(at 0 0 0)
			(layer "F.Fab")
			(hide yes)
			(effects
				(font
					(size 1.27 1.27)
					(thickness 0.15)
				)
			)
		)
		(property "Description" "SMD Chip Resistor, 2.2 kohm, ± 1%, 62.5 mW, 0402 [1005 Metric], Thick Film, General Purpose"
			(at 0 0 0)
			(layer "F.Fab")
			(hide yes)
			(effects
				(font
					(size 1.27 1.27)
					(thickness 0.15)
				)
			)
		)
		(property "MPN" "CR0402-FX-2201GLF"
			(at 0 0 0)
			(unlocked yes)
			(layer "F.Fab")
			(hide yes)
			(effects
				(font
					(size 1 1)
					(thickness 0.15)
				)
			)
		)
		(property "Manufacturer" "Bourns"
			(at 0 0 0)
			(unlocked yes)
			(layer "F.Fab")
			(hide yes)
			(effects
				(font
					(size 1 1)
					(thickness 0.15)
				)
			)
		)
		(property "License" "Apache-2.0"
			(at 0 0 0)
			(unlocked yes)
			(layer "F.Fab")
			(hide yes)
			(effects
				(font
					(size 1 1)
					(thickness 0.15)
				)
			)
		)
		(property "Author" "Antmicro"
			(at 0 0 0)
			(unlocked yes)
			(layer "F.Fab")
			(hide yes)
			(effects
				(font
					(size 1 1)
					(thickness 0.15)
				)
			)
		)
		(property "Val" "2k2"
			(at 0 0 0)
			(unlocked yes)
			(layer "F.Fab")
			(hide yes)
			(effects
				(font
					(size 1 1)
					(thickness 0.15)
				)
			)
		)
		(property "Tolerance" "1%"
			(at 0 0 0)
			(unlocked yes)
			(layer "F.Fab")
			(hide yes)
			(effects
				(font
					(size 1 1)
					(thickness 0.15)
				)
			)
		)
		(sheetname "/SoM_IO/")
		(sheetfile "som_io.kicad_sch")
		(attr smd)
		(fp_rect
			(start -0.925 -0.47)
			(end 0.925 0.47)
			(stroke
				(width 0.05)
				(type default)
			)
			(fill no)
			(layer "F.CrtYd")
		)
		(fp_rect
			(start -0.5 -0.25)
			(end 0.5 0.25)
			(stroke
				(width 0.15)
				(type solid)
			)
			(fill no)
			(layer "F.Fab")
		)
		(fp_text user "Author: Antmicro"
			(at -0.95 4.169 0)
			(layer "F.Fab")
			(effects
				(font
					(size 0.7 0.7)
					(thickness 0.15)
				)
				(justify left bottom)
			)
		)
		(fp_text user "License: Apache-2.0"
			(at -0.95 5.169 0)
			(layer "F.Fab")
			(effects
				(font
					(size 0.7 0.7)
					(thickness 0.15)
				)
				(justify left bottom)
			)
		)
		(fp_text user "${REFERENCE}"
			(at -0.95 3.168 0)
			(layer "F.Fab")
			(effects
				(font
					(size 0.7 0.7)
					(thickness 0.15)
				)
				(justify left bottom)
			)
		)
		(pad "1" smd roundrect
			(at -0.48 0)
			(size 0.59 0.64)
			(layers "F.Cu" "F.Mask" "F.Paste")
			(roundrect_rratio 0.25)
			(net 2 "+3V3")
			(pintype "passive")
		)
		(pad "2" smd roundrect
			(at 0.48 0)
			(size 0.59 0.64)
			(layers "F.Cu" "F.Mask" "F.Paste")
			(roundrect_rratio 0.25)
			(net 561 "/Expansion connector/I2C0.SDA")
			(pintype "passive")
		)
	)
	(footprint "antmicro-footprints:C_0402_1005Metric"
		(layer "F.Cu")
		(at 177.945 110.706 -90)
		(descr "Capacitor SMD 0402")
		(tags "capacitor SMD 0402")
		(property "Reference" "C48"
			(at -2.9 0.325 90)
			(layer "F.SilkS")
			(effects
				(font
					(size 0.7 0.7)
					(thickness 0.15)
				)
				(justify right top)
			)
		)
		(property "Value" "C_100n_0402"
			(at -1.022927 2.155213 90)
			(layer "F.Fab")
			(effects
				(font
					(size 0.7 0.7)
					(thickness 0.15)
				)
				(justify right top)
			)
		)
		(property "Datasheet" "https://www.murata.com/products/productdetail?partno=GRM155R61H104KE14%23"
			(at 0 0 90)
			(layer "F.Fab")
			(hide yes)
			(effects
				(font
					(size 1.27 1.27)
					(thickness 0.15)
				)
			)
		)
		(property "Description" "SMD Multilayer Ceramic Capacitor, 0.1 µF, 50 V, 0402 [1005 Metric], ± 10%, X5R, GRM Series"
			(at 0 0 90)
			(layer "F.Fab")
			(hide yes)
			(effects
				(font
					(size 1.27 1.27)
					(thickness 0.15)
				)
			)
		)
		(property "Manufacturer" "Murata"
			(at 0 0 270)
			(unlocked yes)
			(layer "F.Fab")
			(hide yes)
			(effects
				(font
					(size 1 1)
					(thickness 0.15)
				)
			)
		)
		(property "MPN" "GRM155R61H104KE14D"
			(at 0 0 270)
			(unlocked yes)
			(layer "F.Fab")
			(hide yes)
			(effects
				(font
					(size 1 1)
					(thickness 0.15)
				)
			)
		)
		(property "Val" "100n"
			(at 0 0 270)
			(unlocked yes)
			(layer "F.Fab")
			(hide yes)
			(effects
				(font
					(size 1 1)
					(thickness 0.15)
				)
			)
		)
		(property "License" "Apache-2.0"
			(at 0 0 270)
			(unlocked yes)
			(layer "F.Fab")
			(hide yes)
			(effects
				(font
					(size 1 1)
					(thickness 0.15)
				)
			)
		)
		(property "Author" "Antmicro"
			(at 0 0 270)
			(unlocked yes)
			(layer "F.Fab")
			(hide yes)
			(effects
				(font
					(size 1 1)
					(thickness 0.15)
				)
			)
		)
		(property "Voltage" "50V"
			(at 0 0 270)
			(unlocked yes)
			(layer "F.Fab")
			(hide yes)
			(effects
				(font
					(size 1 1)
					(thickness 0.15)
				)
			)
		)
		(property "Dielectric" "X5R"
			(at 0 0 270)
			(unlocked yes)
			(layer "F.Fab")
			(hide yes)
			(effects
				(font
					(size 1 1)
					(thickness 0.15)
				)
			)
		)
		(sheetname "/DCDC/")
		(sheetfile "dcdc.kicad_sch")
		(attr smd)
		(fp_rect
			(start -0.925 -0.47)
			(end 0.925 0.47)
			(stroke
				(width 0.05)
				(type default)
			)
			(fill no)
			(layer "F.CrtYd")
		)
		(fp_line
			(start -0.494 0.248)
			(end -0.494 -0.25)
			(stroke
				(width 0.15)
				(type solid)
			)
			(layer "F.Fab")
		)
		(fp_line
			(start 0.504 0.248)
			(end -0.494 0.248)
			(stroke
				(width 0.15)
				(type solid)
			)
			(layer "F.Fab")
		)
		(fp_line
			(start -0.494 -0.25)
			(end 0.504 -0.25)
			(stroke
				(width 0.15)
				(type solid)
			)
			(layer "F.Fab")
		)
		(fp_line
			(start 0.504 -0.25)
			(end 0.504 0.248)
			(stroke
				(width 0.15)
				(type solid)
			)
			(layer "F.Fab")
		)
		(fp_text user "License: Apache-2.0"
			(at -0.939 5.799 90)
			(layer "F.Fab")
			(effects
				(font
					(size 0.7 0.7)
					(thickness 0.15)
				)
				(justify right top)
			)
		)
		(fp_text user "${REFERENCE}"
			(at -0.939 4.599 90)
			(layer "F.Fab")
			(effects
				(font
					(size 0.7 0.7)
					(thickness 0.15)
				)
				(justify right top)
			)
		)
		(fp_text user "Author: Antmicro"
			(at -0.939 3.399 90)
			(layer "F.Fab")
			(effects
				(font
					(size 0.7 0.7)
					(thickness 0.15)
				)
				(justify right top)
			)
		)
		(pad "1" smd roundrect
			(at -0.48 0 270)
			(size 0.59 0.64)
			(layers "F.Cu" "F.Mask" "F.Paste")
			(roundrect_rratio 0.25)
			(net 13 "VCC")
			(pintype "passive")
		)
		(pad "2" smd roundrect
			(at 0.48 0 270)
			(size 0.59 0.64)
			(layers "F.Cu" "F.Mask" "F.Paste")
			(roundrect_rratio 0.25)
			(net 1 "GND")
			(pintype "passive")
		)
	)
	(footprint "antmicro-footprints:C_0402_1005Metric"
		(layer "F.Cu")
		(at 97.95 56.37 -90)
		(descr "Capacitor SMD 0402")
		(tags "capacitor SMD 0402")
		(property "Reference" "C41"
			(at -1.12 -0.6 90)
			(layer "F.SilkS")
			(effects
				(font
					(size 0.7 0.7)
					(thickness 0.15)
				)
				(justify right top)
			)
		)
		(property "Value" "C_100n_0402"
			(at -1.022927 2.155213 90)
			(layer "F.Fab")
			(effects
				(font
					(size 0.7 0.7)
					(thickness 0.15)
				)
				(justify right top)
			)
		)
		(property "Datasheet" "https://www.murata.com/products/productdetail?partno=GRM155R61H104KE14%23"
			(at 0 0 90)
			(layer "F.Fab")
			(hide yes)
			(effects
				(font
					(size 1.27 1.27)
					(thickness 0.15)
				)
			)
		)
		(property "Description" "SMD Multilayer Ceramic Capacitor, 0.1 µF, 50 V, 0402 [1005 Metric], ± 10%, X5R, GRM Series"
			(at 0 0 90)
			(layer "F.Fab")
			(hide yes)
			(effects
				(font
					(size 1.27 1.27)
					(thickness 0.15)
				)
			)
		)
		(property "MPN" "GRM155R61H104KE14D"
			(at 0 0 270)
			(unlocked yes)
			(layer "F.Fab")
			(hide yes)
			(effects
				(font
					(size 1 1)
					(thickness 0.15)
				)
			)
		)
		(property "Manufacturer" "Murata"
			(at 0 0 270)
			(unlocked yes)
			(layer "F.Fab")
			(hide yes)
			(effects
				(font
					(size 1 1)
					(thickness 0.15)
				)
			)
		)
		(property "License" "Apache-2.0"
			(at 0 0 270)
			(unlocked yes)
			(layer "F.Fab")
			(hide yes)
			(effects
				(font
					(size 1 1)
					(thickness 0.15)
				)
			)
		)
		(property "Author" "Antmicro"
			(at 0 0 270)
			(unlocked yes)
			(layer "F.Fab")
			(hide yes)
			(effects
				(font
					(size 1 1)
					(thickness 0.15)
				)
			)
		)
		(property "Val" "100n"
			(at 0 0 270)
			(unlocked yes)
			(layer "F.Fab")
			(hide yes)
			(effects
				(font
					(size 1 1)
					(thickness 0.15)
				)
			)
		)
		(property "Voltage" "50V"
			(at 0 0 270)
			(unlocked yes)
			(layer "F.Fab")
			(hide yes)
			(effects
				(font
					(size 1 1)
					(thickness 0.15)
				)
			)
		)
		(property "Dielectric" "X5R"
			(at 0 0 270)
			(unlocked yes)
			(layer "F.Fab")
			(hide yes)
			(effects
				(font
					(size 1 1)
					(thickness 0.15)
				)
			)
		)
		(sheetname "/SoM_Power/")
		(sheetfile "som_power.kicad_sch")
		(attr smd)
		(fp_rect
			(start -0.925 -0.47)
			(end 0.925 0.47)
			(stroke
				(width 0.05)
				(type default)
			)
			(fill no)
			(layer "F.CrtYd")
		)
		(fp_line
			(start -0.494 0.248)
			(end -0.494 -0.25)
			(stroke
				(width 0.15)
				(type solid)
			)
			(layer "F.Fab")
		)
		(fp_line
			(start 0.504 0.248)
			(end -0.494 0.248)
			(stroke
				(width 0.15)
				(type solid)
			)
			(layer "F.Fab")
		)
		(fp_line
			(start -0.494 -0.25)
			(end 0.504 -0.25)
			(stroke
				(width 0.15)
				(type solid)
			)
			(layer "F.Fab")
		)
		(fp_line
			(start 0.504 -0.25)
			(end 0.504 0.248)
			(stroke
				(width 0.15)
				(type solid)
			)
			(layer "F.Fab")
		)
		(fp_text user "${REFERENCE}"
			(at -0.939 4.599 90)
			(layer "F.Fab")
			(effects
				(font
					(size 0.7 0.7)
					(thickness 0.15)
				)
				(justify right top)
			)
		)
		(fp_text user "License: Apache-2.0"
			(at -0.939 5.799 90)
			(layer "F.Fab")
			(effects
				(font
					(size 0.7 0.7)
					(thickness 0.15)
				)
				(justify right top)
			)
		)
		(fp_text user "Author: Antmicro"
			(at -0.939 3.399 90)
			(layer "F.Fab")
			(effects
				(font
					(size 0.7 0.7)
					(thickness 0.15)
				)
				(justify right top)
			)
		)
		(pad "1" smd roundrect
			(at -0.48 0 270)
			(size 0.59 0.64)
			(layers "F.Cu" "F.Mask" "F.Paste")
			(roundrect_rratio 0.25)
			(net 1 "GND")
			(pintype "passive")
		)
		(pad "2" smd roundrect
			(at 0.48 0 270)
			(size 0.59 0.64)
			(layers "F.Cu" "F.Mask" "F.Paste")
			(roundrect_rratio 0.25)
			(net 4 "+3V3_AON")
			(pintype "passive")
		)
	)
)
